(kicad_sch
	(version 20250114)
	(generator "eeschema")
	(generator_version "9.0")
	(paper "A3")
	(title_block
		(title "COM Express 7 Baseboard")
		(date "2025-02-04")
		(rev "1.1.2")
		(company "Antmicro Ltd")
		(comment 1 "www.antmicro.com")
	)
	(text "M.2 key M"
		(exclude_from_sim no)
		(at 198.12 27.94 0)
		(effects
			(font
				(size 2 2)
				(thickness 0.8)
				(bold yes)
			)
			(justify left bottom)
		)
	)
	(text "Swapped polarity of TX and RX lines\nfor easier PCB layout"
		(exclude_from_sim no)
		(at 163.83 173.99 0)
		(effects
			(font
				(size 1.27 1.27)
			)
			(justify left bottom)
		)
	)
	(junction
		(at 193.04 91.44)
		(diameter 0)
		(color 0 0 0 0)
	)
	(junction
		(at 184.15 81.28)
		(diameter 0)
		(color 0 0 0 0)
	)
	(junction
		(at 232.41 166.37)
		(diameter 0)
		(color 0 0 0 0)
	)
	(junction
		(at 267.97 85.09)
		(diameter 0)
		(color 0 0 0 0)
	)
	(junction
		(at 257.81 85.09)
		(diameter 0)
		(color 0 0 0 0)
	)
	(junction
		(at 247.65 85.09)
		(diameter 0)
		(color 0 0 0 0)
	)
	(junction
		(at 184.15 88.9)
		(diameter 0)
		(color 0 0 0 0)
	)
	(junction
		(at 237.49 85.09)
		(diameter 0)
		(color 0 0 0 0)
	)
	(no_connect
		(at 231.14 115.57)
	)
	(no_connect
		(at 231.14 120.65)
	)
	(no_connect
		(at 231.14 118.11)
	)
	(no_connect
		(at 200.66 93.98)
	)
	(bus_entry
		(at 156.21 162.56)
		(size 1.27 1.27)
		(stroke
			(width 0)
			(type default)
		)
	)
	(bus_entry
		(at 156.21 132.08)
		(size 1.27 1.27)
		(stroke
			(width 0)
			(type default)
		)
	)
	(bus_entry
		(at 156.21 109.22)
		(size 1.27 1.27)
		(stroke
			(width 0)
			(type default)
		)
	)
	(bus_entry
		(at 156.21 157.48)
		(size 1.27 1.27)
		(stroke
			(width 0)
			(type default)
		)
	)
	(bus_entry
		(at 156.21 111.76)
		(size 1.27 1.27)
		(stroke
			(width 0)
			(type default)
		)
	)
	(bus_entry
		(at 156.21 139.7)
		(size 1.27 1.27)
		(stroke
			(width 0)
			(type default)
		)
	)
	(bus_entry
		(at 156.21 124.46)
		(size 1.27 1.27)
		(stroke
			(width 0)
			(type default)
		)
	)
	(bus_entry
		(at 156.21 149.86)
		(size 1.27 1.27)
		(stroke
			(width 0)
			(type default)
		)
	)
	(bus_entry
		(at 182.88 101.6)
		(size -1.27 -1.27)
		(stroke
			(width 0)
			(type default)
		)
	)
	(bus_entry
		(at 156.21 119.38)
		(size 1.27 1.27)
		(stroke
			(width 0)
			(type default)
		)
	)
	(bus_entry
		(at 156.21 165.1)
		(size 1.27 1.27)
		(stroke
			(width 0)
			(type default)
		)
	)
	(bus_entry
		(at 156.21 154.94)
		(size 1.27 1.27)
		(stroke
			(width 0)
			(type default)
		)
	)
	(bus_entry
		(at 156.21 127)
		(size 1.27 1.27)
		(stroke
			(width 0)
			(type default)
		)
	)
	(bus_entry
		(at 156.21 142.24)
		(size 1.27 1.27)
		(stroke
			(width 0)
			(type default)
		)
	)
	(bus_entry
		(at 156.21 116.84)
		(size 1.27 1.27)
		(stroke
			(width 0)
			(type default)
		)
	)
	(bus_entry
		(at 156.21 147.32)
		(size 1.27 1.27)
		(stroke
			(width 0)
			(type default)
		)
	)
	(bus_entry
		(at 182.88 104.14)
		(size -1.27 -1.27)
		(stroke
			(width 0)
			(type default)
		)
	)
	(bus_entry
		(at 156.21 134.62)
		(size 1.27 1.27)
		(stroke
			(width 0)
			(type default)
		)
	)
	(wire
		(pts
			(xy 241.3 101.6) (xy 246.38 101.6)
		)
		(stroke
			(width 0)
			(type default)
		)
	)
	(bus
		(pts
			(xy 156.21 85.09) (xy 154.94 83.82)
		)
		(stroke
			(width 0)
			(type default)
		)
	)
	(wire
		(pts
			(xy 247.65 92.71) (xy 247.65 91.44)
		)
		(stroke
			(width 0)
			(type default)
		)
	)
	(wire
		(pts
			(xy 200.66 156.21) (xy 182.88 156.21)
		)
		(stroke
			(width 0)
			(type default)
		)
	)
	(wire
		(pts
			(xy 193.04 91.44) (xy 200.66 91.44)
		)
		(stroke
			(width 0)
			(type default)
		)
	)
	(wire
		(pts
			(xy 157.48 148.59) (xy 180.34 148.59)
		)
		(stroke
			(width 0)
			(type default)
		)
	)
	(bus
		(pts
			(xy 181.61 100.33) (xy 181.61 97.79)
		)
		(stroke
			(width 0)
			(type default)
		)
	)
	(wire
		(pts
			(xy 180.34 163.83) (xy 182.88 166.37)
		)
		(stroke
			(width 0)
			(type default)
		)
	)
	(wire
		(pts
			(xy 200.66 118.11) (xy 182.88 118.11)
		)
		(stroke
			(width 0)
			(type default)
		)
	)
	(wire
		(pts
			(xy 182.88 110.49) (xy 200.66 110.49)
		)
		(stroke
			(width 0)
			(type default)
		)
	)
	(wire
		(pts
			(xy 232.41 88.9) (xy 232.41 85.09)
		)
		(stroke
			(width 0)
			(type default)
		)
	)
	(wire
		(pts
			(xy 157.48 125.73) (xy 180.34 125.73)
		)
		(stroke
			(width 0)
			(type default)
		)
	)
	(bus
		(pts
			(xy 156.21 132.08) (xy 156.21 134.62)
		)
		(stroke
			(width 0)
			(type default)
		)
	)
	(wire
		(pts
			(xy 200.66 104.14) (xy 182.88 104.14)
		)
		(stroke
			(width 0)
			(type default)
		)
	)
	(bus
		(pts
			(xy 180.34 96.52) (xy 149.86 96.52)
		)
		(stroke
			(width 0)
			(type default)
		)
	)
	(wire
		(pts
			(xy 247.65 85.09) (xy 237.49 85.09)
		)
		(stroke
			(width 0)
			(type default)
		)
	)
	(wire
		(pts
			(xy 200.66 101.6) (xy 182.88 101.6)
		)
		(stroke
			(width 0)
			(type default)
		)
	)
	(wire
		(pts
			(xy 182.88 128.27) (xy 200.66 128.27)
		)
		(stroke
			(width 0)
			(type default)
		)
	)
	(wire
		(pts
			(xy 157.48 163.83) (xy 180.34 163.83)
		)
		(stroke
			(width 0)
			(type default)
		)
	)
	(wire
		(pts
			(xy 200.66 120.65) (xy 182.88 120.65)
		)
		(stroke
			(width 0)
			(type default)
		)
	)
	(wire
		(pts
			(xy 200.66 148.59) (xy 182.88 148.59)
		)
		(stroke
			(width 0)
			(type default)
		)
	)
	(wire
		(pts
			(xy 182.88 166.37) (xy 200.66 166.37)
		)
		(stroke
			(width 0)
			(type default)
		)
	)
	(bus
		(pts
			(xy 156.21 119.38) (xy 156.21 124.46)
		)
		(stroke
			(width 0)
			(type default)
		)
	)
	(wire
		(pts
			(xy 157.48 113.03) (xy 180.34 113.03)
		)
		(stroke
			(width 0)
			(type default)
		)
	)
	(wire
		(pts
			(xy 267.97 85.09) (xy 267.97 86.36)
		)
		(stroke
			(width 0)
			(type default)
		)
	)
	(wire
		(pts
			(xy 267.97 81.28) (xy 267.97 85.09)
		)
		(stroke
			(width 0)
			(type default)
		)
	)
	(wire
		(pts
			(xy 267.97 92.71) (xy 267.97 91.44)
		)
		(stroke
			(width 0)
			(type default)
		)
	)
	(wire
		(pts
			(xy 182.88 143.51) (xy 200.66 143.51)
		)
		(stroke
			(width 0)
			(type default)
		)
	)
	(wire
		(pts
			(xy 232.41 166.37) (xy 232.41 163.83)
		)
		(stroke
			(width 0)
			(type default)
		)
	)
	(bus
		(pts
			(xy 156.21 124.46) (xy 156.21 127)
		)
		(stroke
			(width 0)
			(type default)
		)
	)
	(wire
		(pts
			(xy 182.88 125.73) (xy 180.34 128.27)
		)
		(stroke
			(width 0)
			(type default)
		)
	)
	(wire
		(pts
			(xy 157.48 143.51) (xy 180.34 143.51)
		)
		(stroke
			(width 0)
			(type default)
		)
	)
	(wire
		(pts
			(xy 193.04 81.28) (xy 184.15 81.28)
		)
		(stroke
			(width 0)
			(type default)
		)
	)
	(wire
		(pts
			(xy 209.55 198.12) (xy 209.55 200.66)
		)
		(stroke
			(width 0)
			(type default)
		)
	)
	(wire
		(pts
			(xy 182.88 151.13) (xy 200.66 151.13)
		)
		(stroke
			(width 0)
			(type default)
		)
	)
	(bus
		(pts
			(xy 156.21 147.32) (xy 156.21 149.86)
		)
		(stroke
			(width 0)
			(type default)
		)
	)
	(bus
		(pts
			(xy 156.21 139.7) (xy 156.21 142.24)
		)
		(stroke
			(width 0)
			(type default)
		)
	)
	(wire
		(pts
			(xy 184.15 81.28) (xy 184.15 82.55)
		)
		(stroke
			(width 0)
			(type default)
		)
	)
	(wire
		(pts
			(xy 231.14 166.37) (xy 232.41 166.37)
		)
		(stroke
			(width 0)
			(type default)
		)
	)
	(wire
		(pts
			(xy 257.81 85.09) (xy 247.65 85.09)
		)
		(stroke
			(width 0)
			(type default)
		)
	)
	(wire
		(pts
			(xy 157.48 166.37) (xy 180.34 166.37)
		)
		(stroke
			(width 0)
			(type default)
		)
	)
	(wire
		(pts
			(xy 237.49 85.09) (xy 237.49 86.36)
		)
		(stroke
			(width 0)
			(type default)
		)
	)
	(wire
		(pts
			(xy 257.81 85.09) (xy 257.81 86.36)
		)
		(stroke
			(width 0)
			(type default)
		)
	)
	(bus
		(pts
			(xy 156.21 157.48) (xy 156.21 162.56)
		)
		(stroke
			(width 0)
			(type default)
		)
	)
	(wire
		(pts
			(xy 232.41 167.64) (xy 232.41 166.37)
		)
		(stroke
			(width 0)
			(type default)
		)
	)
	(wire
		(pts
			(xy 184.15 80.01) (xy 184.15 81.28)
		)
		(stroke
			(width 0)
			(type default)
		)
	)
	(wire
		(pts
			(xy 180.34 118.11) (xy 182.88 120.65)
		)
		(stroke
			(width 0)
			(type default)
		)
	)
	(wire
		(pts
			(xy 267.97 85.09) (xy 257.81 85.09)
		)
		(stroke
			(width 0)
			(type default)
		)
	)
	(wire
		(pts
			(xy 157.48 110.49) (xy 180.34 110.49)
		)
		(stroke
			(width 0)
			(type default)
		)
	)
	(bus
		(pts
			(xy 156.21 109.22) (xy 156.21 111.76)
		)
		(stroke
			(width 0)
			(type default)
		)
	)
	(bus
		(pts
			(xy 156.21 154.94) (xy 156.21 157.48)
		)
		(stroke
			(width 0)
			(type default)
		)
	)
	(wire
		(pts
			(xy 200.66 140.97) (xy 182.88 140.97)
		)
		(stroke
			(width 0)
			(type default)
		)
	)
	(wire
		(pts
			(xy 237.49 92.71) (xy 237.49 91.44)
		)
		(stroke
			(width 0)
			(type default)
		)
	)
	(wire
		(pts
			(xy 182.88 113.03) (xy 200.66 113.03)
		)
		(stroke
			(width 0)
			(type default)
		)
	)
	(wire
		(pts
			(xy 157.48 140.97) (xy 180.34 140.97)
		)
		(stroke
			(width 0)
			(type default)
		)
	)
	(wire
		(pts
			(xy 149.86 91.44) (xy 193.04 91.44)
		)
		(stroke
			(width 0)
			(type default)
		)
	)
	(wire
		(pts
			(xy 157.48 133.35) (xy 180.34 133.35)
		)
		(stroke
			(width 0)
			(type default)
		)
	)
	(wire
		(pts
			(xy 157.48 156.21) (xy 180.34 156.21)
		)
		(stroke
			(width 0)
			(type default)
		)
	)
	(bus
		(pts
			(xy 156.21 134.62) (xy 156.21 139.7)
		)
		(stroke
			(width 0)
			(type default)
		)
	)
	(wire
		(pts
			(xy 247.65 85.09) (xy 247.65 86.36)
		)
		(stroke
			(width 0)
			(type default)
		)
	)
	(bus
		(pts
			(xy 149.86 83.82) (xy 154.94 83.82)
		)
		(stroke
			(width 0)
			(type default)
		)
	)
	(wire
		(pts
			(xy 231.14 88.9) (xy 232.41 88.9)
		)
		(stroke
			(width 0)
			(type default)
		)
	)
	(wire
		(pts
			(xy 257.81 92.71) (xy 257.81 91.44)
		)
		(stroke
			(width 0)
			(type default)
		)
	)
	(wire
		(pts
			(xy 267.97 74.93) (xy 267.97 76.2)
		)
		(stroke
			(width 0)
			(type default)
		)
	)
	(wire
		(pts
			(xy 182.88 140.97) (xy 180.34 143.51)
		)
		(stroke
			(width 0)
			(type default)
		)
	)
	(wire
		(pts
			(xy 184.15 88.9) (xy 200.66 88.9)
		)
		(stroke
			(width 0)
			(type default)
		)
	)
	(wire
		(pts
			(xy 180.34 110.49) (xy 182.88 113.03)
		)
		(stroke
			(width 0)
			(type default)
		)
	)
	(wire
		(pts
			(xy 180.34 140.97) (xy 182.88 143.51)
		)
		(stroke
			(width 0)
			(type default)
		)
	)
	(wire
		(pts
			(xy 232.41 129.54) (xy 232.41 130.81)
		)
		(stroke
			(width 0)
			(type default)
		)
	)
	(wire
		(pts
			(xy 182.88 133.35) (xy 180.34 135.89)
		)
		(stroke
			(width 0)
			(type default)
		)
	)
	(wire
		(pts
			(xy 149.86 88.9) (xy 162.56 88.9)
		)
		(stroke
			(width 0)
			(type default)
		)
	)
	(wire
		(pts
			(xy 157.48 151.13) (xy 180.34 151.13)
		)
		(stroke
			(width 0)
			(type default)
		)
	)
	(wire
		(pts
			(xy 180.34 133.35) (xy 182.88 135.89)
		)
		(stroke
			(width 0)
			(type default)
		)
	)
	(bus
		(pts
			(xy 156.21 149.86) (xy 156.21 154.94)
		)
		(stroke
			(width 0)
			(type default)
		)
	)
	(wire
		(pts
			(xy 182.88 118.11) (xy 180.34 120.65)
		)
		(stroke
			(width 0)
			(type default)
		)
	)
	(wire
		(pts
			(xy 182.88 135.89) (xy 200.66 135.89)
		)
		(stroke
			(width 0)
			(type default)
		)
	)
	(wire
		(pts
			(xy 182.88 158.75) (xy 200.66 158.75)
		)
		(stroke
			(width 0)
			(type default)
		)
	)
	(bus
		(pts
			(xy 156.21 127) (xy 156.21 132.08)
		)
		(stroke
			(width 0)
			(type default)
		)
	)
	(wire
		(pts
			(xy 184.15 87.63) (xy 184.15 88.9)
		)
		(stroke
			(width 0)
			(type default)
		)
	)
	(wire
		(pts
			(xy 180.34 120.65) (xy 157.48 120.65)
		)
		(stroke
			(width 0)
			(type default)
		)
	)
	(wire
		(pts
			(xy 193.04 87.63) (xy 193.04 91.44)
		)
		(stroke
			(width 0)
			(type default)
		)
	)
	(wire
		(pts
			(xy 182.88 110.49) (xy 180.34 113.03)
		)
		(stroke
			(width 0)
			(type default)
		)
	)
	(wire
		(pts
			(xy 232.41 85.09) (xy 237.49 85.09)
		)
		(stroke
			(width 0)
			(type default)
		)
	)
	(wire
		(pts
			(xy 182.88 148.59) (xy 180.34 151.13)
		)
		(stroke
			(width 0)
			(type default)
		)
	)
	(wire
		(pts
			(xy 193.04 81.28) (xy 193.04 82.55)
		)
		(stroke
			(width 0)
			(type default)
		)
	)
	(bus
		(pts
			(xy 156.21 85.09) (xy 156.21 109.22)
		)
		(stroke
			(width 0)
			(type default)
		)
	)
	(wire
		(pts
			(xy 209.55 198.12) (xy 210.82 198.12)
		)
		(stroke
			(width 0)
			(type default)
		)
	)
	(wire
		(pts
			(xy 200.66 125.73) (xy 182.88 125.73)
		)
		(stroke
			(width 0)
			(type default)
		)
	)
	(bus
		(pts
			(xy 156.21 111.76) (xy 156.21 116.84)
		)
		(stroke
			(width 0)
			(type default)
		)
	)
	(wire
		(pts
			(xy 180.34 156.21) (xy 182.88 158.75)
		)
		(stroke
			(width 0)
			(type default)
		)
	)
	(wire
		(pts
			(xy 231.14 143.51) (xy 232.41 143.51)
		)
		(stroke
			(width 0)
			(type default)
		)
	)
	(wire
		(pts
			(xy 180.34 118.11) (xy 157.48 118.11)
		)
		(stroke
			(width 0)
			(type default)
		)
	)
	(wire
		(pts
			(xy 157.48 135.89) (xy 180.34 135.89)
		)
		(stroke
			(width 0)
			(type default)
		)
	)
	(wire
		(pts
			(xy 232.41 135.89) (xy 232.41 137.16)
		)
		(stroke
			(width 0)
			(type default)
		)
	)
	(wire
		(pts
			(xy 231.14 101.6) (xy 236.22 101.6)
		)
		(stroke
			(width 0)
			(type default)
		)
	)
	(wire
		(pts
			(xy 180.34 148.59) (xy 182.88 151.13)
		)
		(stroke
			(width 0)
			(type default)
		)
	)
	(wire
		(pts
			(xy 180.34 125.73) (xy 182.88 128.27)
		)
		(stroke
			(width 0)
			(type default)
		)
	)
	(bus
		(pts
			(xy 156.21 162.56) (xy 156.21 165.1)
		)
		(stroke
			(width 0)
			(type default)
		)
	)
	(wire
		(pts
			(xy 157.48 128.27) (xy 180.34 128.27)
		)
		(stroke
			(width 0)
			(type default)
		)
	)
	(wire
		(pts
			(xy 200.66 163.83) (xy 182.88 163.83)
		)
		(stroke
			(width 0)
			(type default)
		)
	)
	(wire
		(pts
			(xy 232.41 142.24) (xy 232.41 143.51)
		)
		(stroke
			(width 0)
			(type default)
		)
	)
	(wire
		(pts
			(xy 182.88 163.83) (xy 180.34 166.37)
		)
		(stroke
			(width 0)
			(type default)
		)
	)
	(wire
		(pts
			(xy 232.41 163.83) (xy 231.14 163.83)
		)
		(stroke
			(width 0)
			(type default)
		)
	)
	(wire
		(pts
			(xy 200.66 133.35) (xy 182.88 133.35)
		)
		(stroke
			(width 0)
			(type default)
		)
	)
	(wire
		(pts
			(xy 182.88 156.21) (xy 180.34 158.75)
		)
		(stroke
			(width 0)
			(type default)
		)
	)
	(bus
		(pts
			(xy 181.61 97.79) (xy 180.34 96.52)
		)
		(stroke
			(width 0)
			(type default)
		)
	)
	(wire
		(pts
			(xy 157.48 158.75) (xy 180.34 158.75)
		)
		(stroke
			(width 0)
			(type default)
		)
	)
	(bus
		(pts
			(xy 181.61 102.87) (xy 181.61 100.33)
		)
		(stroke
			(width 0)
			(type default)
		)
	)
	(wire
		(pts
			(xy 167.64 88.9) (xy 184.15 88.9)
		)
		(stroke
			(width 0)
			(type default)
		)
	)
	(bus
		(pts
			(xy 156.21 116.84) (xy 156.21 119.38)
		)
		(stroke
			(width 0)
			(type default)
		)
	)
	(bus
		(pts
			(xy 156.21 142.24) (xy 156.21 147.32)
		)
		(stroke
			(width 0)
			(type default)
		)
	)
	(label "PCIe_{x4}.TX2-"
		(at 158.75 143.51 0)
		(effects
			(font
				(size 1.27 1.27)
			)
			(justify left bottom)
		)
	)
	(label "PCIe_{x4}.TX1-"
		(at 158.75 128.27 0)
		(effects
			(font
				(size 1.27 1.27)
			)
			(justify left bottom)
		)
	)
	(label "PCIe_{x4}.TX1+"
		(at 158.75 125.73 0)
		(effects
			(font
				(size 1.27 1.27)
			)
			(justify left bottom)
		)
	)
	(label "PCIe_{x4}.RX2+"
		(at 158.75 148.59 0)
		(effects
			(font
				(size 1.27 1.27)
			)
			(justify left bottom)
		)
	)
	(label "PCIe_{x4}.TX2+"
		(at 158.75 140.97 0)
		(effects
			(font
				(size 1.27 1.27)
			)
			(justify left bottom)
		)
	)
	(label "PCIe_{x4}.RX1-"
		(at 158.75 135.89 0)
		(effects
			(font
				(size 1.27 1.27)
			)
			(justify left bottom)
		)
	)
	(label "PCIe_{x4}.RX0+"
		(at 158.75 118.11 0)
		(effects
			(font
				(size 1.27 1.27)
			)
			(justify left bottom)
		)
	)
	(label "PCIe_{x4}.RX0-"
		(at 158.75 120.65 0)
		(effects
			(font
				(size 1.27 1.27)
			)
			(justify left bottom)
		)
	)
	(label "PCIE_{REF}.CK+"
		(at 200.66 101.6 180)
		(effects
			(font
				(size 1.27 1.27)
			)
			(justify right bottom)
		)
	)
	(label "PCIe_{x4}.TX0-"
		(at 158.75 113.03 0)
		(effects
			(font
				(size 1.27 1.27)
			)
			(justify left bottom)
		)
	)
	(label "PCIe_{x4}.RX3-"
		(at 158.75 166.37 0)
		(effects
			(font
				(size 1.27 1.27)
			)
			(justify left bottom)
		)
	)
	(label "PCIe_{x4}.TX3+"
		(at 158.75 156.21 0)
		(effects
			(font
				(size 1.27 1.27)
			)
			(justify left bottom)
		)
	)
	(label "PCIe_{x4}.RX2-"
		(at 158.75 151.13 0)
		(effects
			(font
				(size 1.27 1.27)
			)
			(justify left bottom)
		)
	)
	(label "PCIe_{x4}.TX0+"
		(at 158.75 110.49 0)
		(effects
			(font
				(size 1.27 1.27)
			)
			(justify left bottom)
		)
	)
	(label "~{PERST_D}"
		(at 171.45 88.9 0)
		(effects
			(font
				(size 1.27 1.27)
			)
			(justify left bottom)
		)
	)
	(label "M2_3V3"
		(at 232.41 85.09 0)
		(effects
			(font
				(size 1.27 1.27)
			)
			(justify left bottom)
		)
	)
	(label "PCIe_{x4}.TX3-"
		(at 158.75 158.75 0)
		(effects
			(font
				(size 1.27 1.27)
			)
			(justify left bottom)
		)
	)
	(label "PCIE_{REF}.CK-"
		(at 200.66 104.14 180)
		(effects
			(font
				(size 1.27 1.27)
			)
			(justify right bottom)
		)
	)
	(label "PCIe_{x4}.RX1+"
		(at 158.75 133.35 0)
		(effects
			(font
				(size 1.27 1.27)
			)
			(justify left bottom)
		)
	)
	(label "PCIe_{x4}.RX3+"
		(at 158.75 163.83 0)
		(effects
			(font
				(size 1.27 1.27)
			)
			(justify left bottom)
		)
	)
	(hierarchical_label "~{PERST}"
		(shape input)
		(at 149.86 88.9 180)
		(effects
			(font
				(size 1.27 1.27)
			)
			(justify right)
		)
	)
	(hierarchical_label "SUSCLK"
		(shape input)
		(at 246.38 101.6 0)
		(effects
			(font
				(size 1.27 1.27)
			)
			(justify left)
		)
	)
	(hierarchical_label "PCIE_{REF}{PCIe_{REF}}"
		(shape input)
		(at 149.86 96.52 180)
		(effects
			(font
				(size 1.27 1.27)
			)
			(justify right)
		)
	)
	(hierarchical_label "PCIe_{x4}{PCIe}"
		(shape input)
		(at 149.86 83.82 180)
		(effects
			(font
				(size 1.27 1.27)
			)
			(justify right)
		)
	)
	(hierarchical_label "~{CLKREQ}"
		(shape output)
		(at 149.86 91.44 180)
		(effects
			(font
				(size 1.27 1.27)
			)
			(justify right)
		)
	)
	(symbol
		(lib_id "antmicroResistors0402:R_0R_0402")
		(at 162.56 88.9 0)
		(unit 1)
		(exclude_from_sim no)
		(in_bom yes)
		(on_board yes)
		(dnp no)
		(property "Reference" "R120"
			(at 160.02 87.63 0)
			(effects
				(font
					(size 1.27 1.27)
					(thickness 0.15)
				)
			)
		)
		(property "Value" "R_0R_0402"
			(at 182.88 101.6 0)
			(effects
				(font
					(size 1.27 1.27)
					(thickness 0.15)
				)
				(justify left bottom)
				(hide yes)
			)
		)
		(property "Footprint" "antmicro-footprints:R_0402_1005Metric"
			(at 182.88 104.14 0)
			(effects
				(font
					(size 1.27 1.27)
					(thickness 0.15)
				)
				(justify left bottom)
				(hide yes)
			)
		)
		(property "Datasheet" "https://industrial.panasonic.com/cdbs/www-data/pdf/RDA0000/AOA0000C301.pdf"
			(at 182.88 106.68 0)
			(effects
				(font
					(size 1.27 1.27)
					(thickness 0.15)
				)
				(justify left bottom)
				(hide yes)
			)
		)
		(property "Description" ""
			(at 162.56 88.9 0)
			(effects
				(font
					(size 1.27 1.27)
				)
				(hide yes)
			)
		)
		(property "MPN" "ERJ2GE0R00X"
			(at 182.88 109.22 0)
			(effects
				(font
					(size 1.27 1.27)
					(thickness 0.15)
				)
				(justify left bottom)
				(hide yes)
			)
		)
		(property "Manufacturer" "Panasonic"
			(at 182.88 111.76 0)
			(effects
				(font
					(size 1.27 1.27)
					(thickness 0.15)
				)
				(justify left bottom)
				(hide yes)
			)
		)
		(property "License" "Apache-2.0"
			(at 182.88 114.3 0)
			(effects
				(font
					(size 1.27 1.27)
					(thickness 0.15)
				)
				(justify left bottom)
				(hide yes)
			)
		)
		(property "Author" "Antmicro"
			(at 182.88 116.84 0)
			(effects
				(font
					(size 1.27 1.27)
					(thickness 0.15)
				)
				(justify left bottom)
				(hide yes)
			)
		)
		(property "Val" "0R"
			(at 168.91 87.63 0)
			(effects
				(font
					(size 1.27 1.27)
					(thickness 0.15)
				)
			)
		)
		(property "Tolerance" "~"
			(at 182.88 99.06 0)
			(effects
				(font
					(size 1.27 1.27)
				)
				(justify left bottom)
				(hide yes)
			)
		)
		(property "Current" "1A"
			(at 182.88 119.38 0)
			(effects
				(font
					(size 1.27 1.27)
					(thickness 0.15)
				)
				(justify left bottom)
				(hide yes)
			)
		)
		(property "Public" "False"
			(at 182.88 119.38 0)
			(effects
				(font
					(size 1.27 1.27)
				)
				(justify left bottom)
				(hide yes)
			)
		)
		(pin "1"
		)
		(pin "2"
		)
		(instances
			(project "com-express-7-baseboard"
				(path ""
					(reference "R120")
					(unit 1)
				)
			)
		)
	)
	(symbol
		(lib_id "antmicropower:+3V3")
		(at 232.41 129.54 0)
		(unit 1)
		(exclude_from_sim no)
		(in_bom yes)
		(on_board yes)
		(dnp no)
		(property "Reference" "#PWR0158"
			(at 232.41 133.35 0)
			(effects
				(font
					(size 1.27 1.27)
				)
				(justify left bottom)
				(hide yes)
			)
		)
		(property "Value" "+3V3"
			(at 229.87 125.73 0)
			(effects
				(font
					(size 1.27 1.27)
				)
				(justify left)
			)
		)
		(property "Footprint" ""
			(at 232.41 129.54 0)
			(effects
				(font
					(size 1.27 1.27)
				)
				(justify left bottom)
				(hide yes)
			)
		)
		(property "Datasheet" ""
			(at 232.41 129.54 0)
			(effects
				(font
					(size 1.27 1.27)
				)
				(justify left bottom)
				(hide yes)
			)
		)
		(property "Description" ""
			(at 232.41 129.54 0)
			(effects
				(font
					(size 1.27 1.27)
				)
				(hide yes)
			)
		)
		(property "Author" "Antmicro"
			(at 247.65 132.08 0)
			(effects
				(font
					(size 1.27 1.27)
					(thickness 0.15)
				)
				(justify left bottom)
				(hide yes)
			)
		)
		(property "License" "Apache-2.0"
			(at 247.65 134.62 0)
			(effects
				(font
					(size 1.27 1.27)
					(thickness 0.15)
				)
				(justify left bottom)
				(hide yes)
			)
		)
		(pin "1"
		)
		(instances
			(project "com-express-7-baseboard"
				(path ""
					(reference "#PWR0158")
					(unit 1)
				)
			)
		)
	)
	(symbol
		(lib_id "antmicroCapacitors0603:C_22u_16V_0603")
		(at 267.97 91.44 90)
		(unit 1)
		(exclude_from_sim no)
		(in_bom yes)
		(on_board yes)
		(dnp no)
		(fields_autoplaced yes)
		(property "Reference" "C74"
			(at 270.51 87.6235 90)
			(effects
				(font
					(size 1.27 1.27)
					(thickness 0.15)
				)
				(justify right)
			)
		)
		(property "Value" "C_22u_16V_0603"
			(at 278.13 71.12 0)
			(effects
				(font
					(size 1.27 1.27)
					(thickness 0.15)
				)
				(justify left bottom)
				(hide yes)
			)
		)
		(property "Footprint" "antmicro-footprints:C_0603_1608Metric"
			(at 280.67 71.12 0)
			(effects
				(font
					(size 1.27 1.27)
					(thickness 0.15)
				)
				(justify left bottom)
				(hide yes)
			)
		)
		(property "Datasheet" "https://product.samsungsem.com/mlcc/CL10A226MO7JZN.do"
			(at 283.21 71.12 0)
			(effects
				(font
					(size 1.27 1.27)
					(thickness 0.15)
				)
				(justify left bottom)
				(hide yes)
			)
		)
		(property "Description" ""
			(at 267.97 91.44 0)
			(effects
				(font
					(size 1.27 1.27)
				)
				(hide yes)
			)
		)
		(property "MPN" "CL10A226MO7JZNC"
			(at 285.75 71.12 0)
			(effects
				(font
					(size 1.27 1.27)
					(thickness 0.15)
				)
				(justify left bottom)
				(hide yes)
			)
		)
		(property "Manufacturer" "Samsung Electro-Mechanics"
			(at 288.29 71.12 0)
			(effects
				(font
					(size 1.27 1.27)
					(thickness 0.15)
				)
				(justify left bottom)
				(hide yes)
			)
		)
		(property "License" "Apache-2.0"
			(at 290.83 71.12 0)
			(effects
				(font
					(size 1.27 1.27)
					(thickness 0.15)
				)
				(justify left bottom)
				(hide yes)
			)
		)
		(property "Author" "Antmicro"
			(at 293.37 71.12 0)
			(effects
				(font
					(size 1.27 1.27)
					(thickness 0.15)
				)
				(justify left bottom)
				(hide yes)
			)
		)
		(property "Val" "22u"
			(at 270.51 90.1635 90)
			(effects
				(font
					(size 1.27 1.27)
					(thickness 0.15)
				)
				(justify right)
			)
		)
		(property "Voltage" "16V"
			(at 295.91 71.12 0)
			(effects
				(font
					(size 1.27 1.27)
				)
				(justify left bottom)
				(hide yes)
			)
		)
		(property "Dielectric" ""
			(at 298.45 71.12 0)
			(effects
				(font
					(size 1.27 1.27)
				)
				(justify left bottom)
				(hide yes)
			)
		)
		(property "Public" "False"
			(at 300.99 71.12 0)
			(effects
				(font
					(size 1.27 1.27)
				)
				(justify left bottom)
				(hide yes)
			)
		)
		(pin "2"
		)
		(pin "1"
		)
		(instances
			(project "com-express-7-baseboard"
				(path ""
					(reference "C74")
					(unit 1)
				)
			)
		)
	)
	(symbol
		(lib_id "antmicropower:GND")
		(at 209.55 200.66 0)
		(unit 1)
		(exclude_from_sim no)
		(in_bom yes)
		(on_board yes)
		(dnp no)
		(property "Reference" "#PWR0166"
			(at 209.55 207.01 0)
			(effects
				(font
					(size 1.27 1.27)
				)
				(justify left bottom)
				(hide yes)
			)
		)
		(property "Value" "GND"
			(at 207.645 205.74 0)
			(effects
				(font
					(size 1.27 1.27)
				)
				(justify left bottom)
			)
		)
		(property "Footprint" ""
			(at 209.55 200.66 0)
			(effects
				(font
					(size 1.27 1.27)
				)
				(justify left bottom)
				(hide yes)
			)
		)
		(property "Datasheet" ""
			(at 209.55 200.66 0)
			(effects
				(font
					(size 1.27 1.27)
				)
				(justify left bottom)
				(hide yes)
			)
		)
		(property "Description" ""
			(at 209.55 200.66 0)
			(effects
				(font
					(size 1.27 1.27)
				)
				(hide yes)
			)
		)
		(property "Author" "Antmicro"
			(at 218.44 208.28 0)
			(effects
				(font
					(size 1.27 1.27)
					(thickness 0.15)
				)
				(justify left bottom)
				(hide yes)
			)
		)
		(property "License" "Apache-2.0"
			(at 218.44 210.82 0)
			(effects
				(font
					(size 1.27 1.27)
					(thickness 0.15)
				)
				(justify left bottom)
				(hide yes)
			)
		)
		(pin "1"
		)
		(instances
			(project "com-express-7-baseboard"
				(path ""
					(reference "#PWR0166")
					(unit 1)
				)
			)
		)
	)
	(symbol
		(lib_id "antmicroCapacitors0603:C_22u_16V_0603")
		(at 257.81 91.44 90)
		(unit 1)
		(exclude_from_sim no)
		(in_bom yes)
		(on_board yes)
		(dnp no)
		(fields_autoplaced yes)
		(property "Reference" "C73"
			(at 260.35 87.6235 90)
			(effects
				(font
					(size 1.27 1.27)
					(thickness 0.15)
				)
				(justify right)
			)
		)
		(property "Value" "C_22u_16V_0603"
			(at 267.97 71.12 0)
			(effects
				(font
					(size 1.27 1.27)
					(thickness 0.15)
				)
				(justify left bottom)
				(hide yes)
			)
		)
		(property "Footprint" "antmicro-footprints:C_0603_1608Metric"
			(at 270.51 71.12 0)
			(effects
				(font
					(size 1.27 1.27)
					(thickness 0.15)
				)
				(justify left bottom)
				(hide yes)
			)
		)
		(property "Datasheet" "https://product.samsungsem.com/mlcc/CL10A226MO7JZN.do"
			(at 273.05 71.12 0)
			(effects
				(font
					(size 1.27 1.27)
					(thickness 0.15)
				)
				(justify left bottom)
				(hide yes)
			)
		)
		(property "Description" ""
			(at 257.81 91.44 0)
			(effects
				(font
					(size 1.27 1.27)
				)
				(hide yes)
			)
		)
		(property "MPN" "CL10A226MO7JZNC"
			(at 275.59 71.12 0)
			(effects
				(font
					(size 1.27 1.27)
					(thickness 0.15)
				)
				(justify left bottom)
				(hide yes)
			)
		)
		(property "Manufacturer" "Samsung Electro-Mechanics"
			(at 278.13 71.12 0)
			(effects
				(font
					(size 1.27 1.27)
					(thickness 0.15)
				)
				(justify left bottom)
				(hide yes)
			)
		)
		(property "License" "Apache-2.0"
			(at 280.67 71.12 0)
			(effects
				(font
					(size 1.27 1.27)
					(thickness 0.15)
				)
				(justify left bottom)
				(hide yes)
			)
		)
		(property "Author" "Antmicro"
			(at 283.21 71.12 0)
			(effects
				(font
					(size 1.27 1.27)
					(thickness 0.15)
				)
				(justify left bottom)
				(hide yes)
			)
		)
		(property "Val" "22u"
			(at 260.35 90.1635 90)
			(effects
				(font
					(size 1.27 1.27)
					(thickness 0.15)
				)
				(justify right)
			)
		)
		(property "Voltage" "16V"
			(at 285.75 71.12 0)
			(effects
				(font
					(size 1.27 1.27)
				)
				(justify left bottom)
				(hide yes)
			)
		)
		(property "Dielectric" ""
			(at 288.29 71.12 0)
			(effects
				(font
					(size 1.27 1.27)
				)
				(justify left bottom)
				(hide yes)
			)
		)
		(property "Public" "False"
			(at 290.83 71.12 0)
			(effects
				(font
					(size 1.27 1.27)
				)
				(justify left bottom)
				(hide yes)
			)
		)
		(pin "2"
		)
		(pin "1"
		)
		(instances
			(project "com-express-7-baseboard"
				(path ""
					(reference "C73")
					(unit 1)
				)
			)
		)
	)
	(symbol
		(lib_id "antmicroResistors0402:R_10k_0402")
		(at 193.04 87.63 90)
		(unit 1)
		(exclude_from_sim no)
		(in_bom yes)
		(on_board yes)
		(dnp no)
		(fields_autoplaced yes)
		(property "Reference" "R122"
			(at 195.58 82.55 90)
			(effects
				(font
					(size 1.27 1.27)
					(thickness 0.15)
				)
				(justify right)
			)
		)
		(property "Value" "R_10k_0402"
			(at 205.74 67.31 0)
			(effects
				(font
					(size 1.27 1.27)
					(thickness 0.15)
				)
				(justify left bottom)
				(hide yes)
			)
		)
		(property "Footprint" "antmicro-footprints:R_0402_1005Metric"
			(at 208.28 67.31 0)
			(effects
				(font
					(size 1.27 1.27)
					(thickness 0.15)
				)
				(justify left bottom)
				(hide yes)
			)
		)
		(property "Datasheet" "https://www.bourns.com/docs/product-datasheets/cr.pdf"
			(at 210.82 67.31 0)
			(effects
				(font
					(size 1.27 1.27)
					(thickness 0.15)
				)
				(justify left bottom)
				(hide yes)
			)
		)
		(property "Description" ""
			(at 193.04 87.63 0)
			(effects
				(font
					(size 1.27 1.27)
				)
				(hide yes)
			)
		)
		(property "MPN" "CR0402-FX-1002GLF"
			(at 213.36 67.31 0)
			(effects
				(font
					(size 1.27 1.27)
					(thickness 0.15)
				)
				(justify left bottom)
				(hide yes)
			)
		)
		(property "Manufacturer" "Bourns"
			(at 215.9 67.31 0)
			(effects
				(font
					(size 1.27 1.27)
					(thickness 0.15)
				)
				(justify left bottom)
				(hide yes)
			)
		)
		(property "License" "Apache-2.0"
			(at 218.44 67.31 0)
			(effects
				(font
					(size 1.27 1.27)
					(thickness 0.15)
				)
				(justify left bottom)
				(hide yes)
			)
		)
		(property "Author" "Antmicro"
			(at 220.98 67.31 0)
			(effects
				(font
					(size 1.27 1.27)
					(thickness 0.15)
				)
				(justify left bottom)
				(hide yes)
			)
		)
		(property "Val" "10k"
			(at 195.58 85.09 90)
			(effects
				(font
					(size 1.27 1.27)
					(thickness 0.15)
				)
				(justify right)
			)
		)
		(property "Tolerance" "1%"
			(at 203.2 67.31 0)
			(effects
				(font
					(size 1.27 1.27)
				)
				(justify left bottom)
				(hide yes)
			)
		)
		(property "Public" "False"
			(at 223.52 67.31 0)
			(effects
				(font
					(size 1.27 1.27)
				)
				(justify left bottom)
				(hide yes)
			)
		)
		(pin "2"
		)
		(pin "1"
		)
		(instances
			(project "com-express-7-baseboard"
				(path ""
					(reference "R122")
					(unit 1)
				)
			)
		)
	)
	(symbol
		(lib_id "antmicropower:+3V3")
		(at 267.97 74.93 0)
		(unit 1)
		(exclude_from_sim no)
		(in_bom yes)
		(on_board yes)
		(dnp no)
		(property "Reference" "#PWR0163"
			(at 267.97 78.74 0)
			(effects
				(font
					(size 1.27 1.27)
				)
				(justify left bottom)
				(hide yes)
			)
		)
		(property "Value" "+3V3"
			(at 265.43 71.12 0)
			(effects
				(font
					(size 1.27 1.27)
				)
				(justify left)
			)
		)
		(property "Footprint" ""
			(at 267.97 74.93 0)
			(effects
				(font
					(size 1.27 1.27)
				)
				(justify left bottom)
				(hide yes)
			)
		)
		(property "Datasheet" ""
			(at 267.97 74.93 0)
			(effects
				(font
					(size 1.27 1.27)
				)
				(justify left bottom)
				(hide yes)
			)
		)
		(property "Description" ""
			(at 267.97 74.93 0)
			(effects
				(font
					(size 1.27 1.27)
				)
				(hide yes)
			)
		)
		(property "Author" "Antmicro"
			(at 283.21 77.47 0)
			(effects
				(font
					(size 1.27 1.27)
					(thickness 0.15)
				)
				(justify left bottom)
				(hide yes)
			)
		)
		(property "License" "Apache-2.0"
			(at 283.21 80.01 0)
			(effects
				(font
					(size 1.27 1.27)
					(thickness 0.15)
				)
				(justify left bottom)
				(hide yes)
			)
		)
		(pin "1"
		)
		(instances
			(project "com-express-7-baseboard"
				(path ""
					(reference "#PWR0163")
					(unit 1)
				)
			)
		)
	)
	(symbol
		(lib_id "antmicropower:GND")
		(at 267.97 92.71 0)
		(unit 1)
		(exclude_from_sim no)
		(in_bom yes)
		(on_board yes)
		(dnp no)
		(property "Reference" "#PWR0164"
			(at 267.97 99.06 0)
			(effects
				(font
					(size 1.27 1.27)
				)
				(justify left bottom)
				(hide yes)
			)
		)
		(property "Value" "GND"
			(at 266.065 97.79 0)
			(effects
				(font
					(size 1.27 1.27)
				)
				(justify left bottom)
			)
		)
		(property "Footprint" ""
			(at 267.97 92.71 0)
			(effects
				(font
					(size 1.27 1.27)
				)
				(justify left bottom)
				(hide yes)
			)
		)
		(property "Datasheet" ""
			(at 267.97 92.71 0)
			(effects
				(font
					(size 1.27 1.27)
				)
				(justify left bottom)
				(hide yes)
			)
		)
		(property "Description" ""
			(at 267.97 92.71 0)
			(effects
				(font
					(size 1.27 1.27)
				)
				(hide yes)
			)
		)
		(property "Author" "Antmicro"
			(at 276.86 100.33 0)
			(effects
				(font
					(size 1.27 1.27)
					(thickness 0.15)
				)
				(justify left bottom)
				(hide yes)
			)
		)
		(property "License" "Apache-2.0"
			(at 276.86 102.87 0)
			(effects
				(font
					(size 1.27 1.27)
					(thickness 0.15)
				)
				(justify left bottom)
				(hide yes)
			)
		)
		(pin "1"
		)
		(instances
			(project "com-express-7-baseboard"
				(path ""
					(reference "#PWR0164")
					(unit 1)
				)
			)
		)
	)
	(symbol
		(lib_id "antmicroMechanicalParts:Spacer_Drill3.7mm_H2.5mm_9774025151R")
		(at 210.82 198.12 0)
		(mirror x)
		(unit 1)
		(exclude_from_sim no)
		(in_bom yes)
		(on_board yes)
		(dnp no)
		(property "Reference" "H2"
			(at 220.98 196.85 0)
			(effects
				(font
					(size 1.27 1.27)
					(thickness 0.15)
				)
			)
		)
		(property "Value" "Spacer_Drill3.7mm_H2.5mm_9774025151R"
			(at 240.03 199.39 0)
			(effects
				(font
					(size 1.27 1.27)
					(thickness 0.15)
				)
			)
		)
		(property "Footprint" "antmicro-footprints:Spacer_Drill3.7mm_H2.5mm_9774025151R"
			(at 233.68 190.5 0)
			(effects
				(font
					(size 1.27 1.27)
					(thickness 0.15)
				)
				(justify left bottom)
				(hide yes)
			)
		)
		(property "Datasheet" "https://www.we-online.com/components/products/datasheet/9774025151R.pdf"
			(at 233.68 187.96 0)
			(effects
				(font
					(size 1.27 1.27)
					(thickness 0.15)
				)
				(justify left bottom)
				(hide yes)
			)
		)
		(property "Description" ""
			(at 210.82 198.12 0)
			(effects
				(font
					(size 1.27 1.27)
				)
				(hide yes)
			)
		)
		(property "Manufacturer" "Würth Elektronik"
			(at 233.68 185.42 0)
			(effects
				(font
					(size 1.27 1.27)
					(thickness 0.15)
				)
				(justify left bottom)
				(hide yes)
			)
		)
		(property "MPN" "9774025151R"
			(at 233.68 182.88 0)
			(effects
				(font
					(size 1.27 1.27)
					(thickness 0.15)
				)
				(justify left bottom)
				(hide yes)
			)
		)
		(property "Author" "Antmicro"
			(at 233.68 180.34 0)
			(effects
				(font
					(size 1.27 1.27)
					(thickness 0.15)
				)
				(justify left bottom)
				(hide yes)
			)
		)
		(property "License" "Apache-2.0"
			(at 233.68 177.8 0)
			(effects
				(font
					(size 1.27 1.27)
					(thickness 0.15)
				)
				(justify left bottom)
				(hide yes)
			)
		)
		(property "Public" "False"
			(at 233.68 185.42 0)
			(effects
				(font
					(size 1.27 1.27)
				)
				(justify left bottom)
				(hide yes)
			)
		)
		(pin "1"
		)
		(instances
			(project "com-express-7-baseboard"
				(path ""
					(reference "H2")
					(unit 1)
				)
			)
		)
	)
	(symbol
		(lib_id "antmicroResistors0402:R_0R_0402")
		(at 236.22 101.6 0)
		(unit 1)
		(exclude_from_sim no)
		(in_bom yes)
		(on_board yes)
		(dnp no)
		(property "Reference" "R124"
			(at 233.68 100.33 0)
			(effects
				(font
					(size 1.27 1.27)
					(thickness 0.15)
				)
			)
		)
		(property "Value" "R_0R_0402"
			(at 256.54 114.3 0)
			(effects
				(font
					(size 1.27 1.27)
					(thickness 0.15)
				)
				(justify left bottom)
				(hide yes)
			)
		)
		(property "Footprint" "antmicro-footprints:R_0402_1005Metric"
			(at 256.54 116.84 0)
			(effects
				(font
					(size 1.27 1.27)
					(thickness 0.15)
				)
				(justify left bottom)
				(hide yes)
			)
		)
		(property "Datasheet" "https://industrial.panasonic.com/cdbs/www-data/pdf/RDA0000/AOA0000C301.pdf"
			(at 256.54 119.38 0)
			(effects
				(font
					(size 1.27 1.27)
					(thickness 0.15)
				)
				(justify left bottom)
				(hide yes)
			)
		)
		(property "Description" ""
			(at 236.22 101.6 0)
			(effects
				(font
					(size 1.27 1.27)
				)
				(hide yes)
			)
		)
		(property "MPN" "ERJ2GE0R00X"
			(at 256.54 121.92 0)
			(effects
				(font
					(size 1.27 1.27)
					(thickness 0.15)
				)
				(justify left bottom)
				(hide yes)
			)
		)
		(property "Manufacturer" "Panasonic"
			(at 256.54 124.46 0)
			(effects
				(font
					(size 1.27 1.27)
					(thickness 0.15)
				)
				(justify left bottom)
				(hide yes)
			)
		)
		(property "License" "Apache-2.0"
			(at 256.54 127 0)
			(effects
				(font
					(size 1.27 1.27)
					(thickness 0.15)
				)
				(justify left bottom)
				(hide yes)
			)
		)
		(property "Author" "Antmicro"
			(at 256.54 129.54 0)
			(effects
				(font
					(size 1.27 1.27)
					(thickness 0.15)
				)
				(justify left bottom)
				(hide yes)
			)
		)
		(property "Val" "0R"
			(at 242.57 100.33 0)
			(effects
				(font
					(size 1.27 1.27)
					(thickness 0.15)
				)
			)
		)
		(property "Tolerance" "~"
			(at 256.54 111.76 0)
			(effects
				(font
					(size 1.27 1.27)
				)
				(justify left bottom)
				(hide yes)
			)
		)
		(property "Current" "1A"
			(at 256.54 132.08 0)
			(effects
				(font
					(size 1.27 1.27)
					(thickness 0.15)
				)
				(justify left bottom)
				(hide yes)
			)
		)
		(property "Public" "False"
			(at 256.54 132.08 0)
			(effects
				(font
					(size 1.27 1.27)
				)
				(justify left bottom)
				(hide yes)
			)
		)
		(pin "1"
		)
		(pin "2"
		)
		(instances
			(project "com-express-7-baseboard"
				(path ""
					(reference "R124")
					(unit 1)
				)
			)
		)
	)
	(symbol
		(lib_id "antmicroResistors0402:R_220R_0402")
		(at 232.41 135.89 90)
		(unit 1)
		(exclude_from_sim no)
		(in_bom yes)
		(on_board yes)
		(dnp no)
		(property "Reference" "R123"
			(at 233.68 132.08 90)
			(effects
				(font
					(size 1.27 1.27)
					(thickness 0.15)
				)
				(justify right)
			)
		)
		(property "Value" "R_220R_0402"
			(at 245.11 115.57 0)
			(effects
				(font
					(size 1.27 1.27)
					(thickness 0.15)
				)
				(justify left bottom)
				(hide yes)
			)
		)
		(property "Footprint" "antmicro-footprints:R_0402_1005Metric"
			(at 247.65 115.57 0)
			(effects
				(font
					(size 1.27 1.27)
					(thickness 0.15)
				)
				(justify left bottom)
				(hide yes)
			)
		)
		(property "Datasheet" "https://www.bourns.com/docs/product-datasheets/cr.pdf"
			(at 250.19 115.57 0)
			(effects
				(font
					(size 1.27 1.27)
					(thickness 0.15)
				)
				(justify left bottom)
				(hide yes)
			)
		)
		(property "Description" ""
			(at 232.41 135.89 0)
			(effects
				(font
					(size 1.27 1.27)
				)
				(hide yes)
			)
		)
		(property "MPN" "CR0402-FX-2200GLF"
			(at 252.73 115.57 0)
			(effects
				(font
					(size 1.27 1.27)
					(thickness 0.15)
				)
				(justify left bottom)
				(hide yes)
			)
		)
		(property "Manufacturer" "Bourns"
			(at 255.27 115.57 0)
			(effects
				(font
					(size 1.27 1.27)
					(thickness 0.15)
				)
				(justify left bottom)
				(hide yes)
			)
		)
		(property "License" "Apache-2.0"
			(at 257.81 115.57 0)
			(effects
				(font
					(size 1.27 1.27)
					(thickness 0.15)
				)
				(justify left bottom)
				(hide yes)
			)
		)
		(property "Author" "Antmicro"
			(at 260.35 115.57 0)
			(effects
				(font
					(size 1.27 1.27)
					(thickness 0.15)
				)
				(justify left bottom)
				(hide yes)
			)
		)
		(property "Val" "220R"
			(at 233.68 134.62 90)
			(effects
				(font
					(size 1.27 1.27)
					(thickness 0.15)
				)
				(justify right)
			)
		)
		(property "Tolerance" "1%"
			(at 242.57 115.57 0)
			(effects
				(font
					(size 1.27 1.27)
				)
				(justify left bottom)
				(hide yes)
			)
		)
		(property "Public" "False"
			(at 262.89 115.57 0)
			(effects
				(font
					(size 1.27 1.27)
				)
				(justify left bottom)
				(hide yes)
			)
		)
		(pin "2"
		)
		(pin "1"
		)
		(instances
			(project "com-express-7-baseboard"
				(path ""
					(reference "R123")
					(unit 1)
				)
			)
		)
	)
	(symbol
		(lib_id "antmicroResistors0402:R_10k_0402")
		(at 184.15 87.63 90)
		(unit 1)
		(exclude_from_sim no)
		(in_bom yes)
		(on_board yes)
		(dnp yes)
		(fields_autoplaced yes)
		(property "Reference" "R121"
			(at 186.69 82.55 90)
			(effects
				(font
					(size 1.27 1.27)
					(thickness 0.15)
				)
				(justify right)
			)
		)
		(property "Value" "R_10k_0402"
			(at 196.85 67.31 0)
			(effects
				(font
					(size 1.27 1.27)
					(thickness 0.15)
				)
				(justify left bottom)
				(hide yes)
			)
		)
		(property "Footprint" "antmicro-footprints:R_0402_1005Metric"
			(at 199.39 67.31 0)
			(effects
				(font
					(size 1.27 1.27)
					(thickness 0.15)
				)
				(justify left bottom)
				(hide yes)
			)
		)
		(property "Datasheet" "https://www.bourns.com/docs/product-datasheets/cr.pdf"
			(at 201.93 67.31 0)
			(effects
				(font
					(size 1.27 1.27)
					(thickness 0.15)
				)
				(justify left bottom)
				(hide yes)
			)
		)
		(property "Description" ""
			(at 184.15 87.63 0)
			(effects
				(font
					(size 1.27 1.27)
				)
				(hide yes)
			)
		)
		(property "MPN" "CR0402-FX-1002GLF"
			(at 204.47 67.31 0)
			(effects
				(font
					(size 1.27 1.27)
					(thickness 0.15)
				)
				(justify left bottom)
				(hide yes)
			)
		)
		(property "Manufacturer" "Bourns"
			(at 207.01 67.31 0)
			(effects
				(font
					(size 1.27 1.27)
					(thickness 0.15)
				)
				(justify left bottom)
				(hide yes)
			)
		)
		(property "License" "Apache-2.0"
			(at 209.55 67.31 0)
			(effects
				(font
					(size 1.27 1.27)
					(thickness 0.15)
				)
				(justify left bottom)
				(hide yes)
			)
		)
		(property "Author" "Antmicro"
			(at 212.09 67.31 0)
			(effects
				(font
					(size 1.27 1.27)
					(thickness 0.15)
				)
				(justify left bottom)
				(hide yes)
			)
		)
		(property "Val" "10k"
			(at 186.69 85.09 90)
			(effects
				(font
					(size 1.27 1.27)
					(thickness 0.15)
				)
				(justify right)
			)
		)
		(property "Tolerance" "1%"
			(at 194.31 67.31 0)
			(effects
				(font
					(size 1.27 1.27)
				)
				(justify left bottom)
				(hide yes)
			)
		)
		(property "Public" "False"
			(at 214.63 67.31 0)
			(effects
				(font
					(size 1.27 1.27)
				)
				(justify left bottom)
				(hide yes)
			)
		)
		(pin "2"
		)
		(pin "1"
		)
		(instances
			(project "com-express-7-baseboard"
				(path ""
					(reference "R121")
					(unit 1)
				)
			)
		)
	)
	(symbol
		(lib_id "antmicropower:GND")
		(at 237.49 92.71 0)
		(unit 1)
		(exclude_from_sim no)
		(in_bom yes)
		(on_board yes)
		(dnp no)
		(property "Reference" "#PWR0160"
			(at 237.49 99.06 0)
			(effects
				(font
					(size 1.27 1.27)
				)
				(justify left bottom)
				(hide yes)
			)
		)
		(property "Value" "GND"
			(at 235.585 97.79 0)
			(effects
				(font
					(size 1.27 1.27)
				)
				(justify left bottom)
			)
		)
		(property "Footprint" ""
			(at 237.49 92.71 0)
			(effects
				(font
					(size 1.27 1.27)
				)
				(justify left bottom)
				(hide yes)
			)
		)
		(property "Datasheet" ""
			(at 237.49 92.71 0)
			(effects
				(font
					(size 1.27 1.27)
				)
				(justify left bottom)
				(hide yes)
			)
		)
		(property "Description" ""
			(at 237.49 92.71 0)
			(effects
				(font
					(size 1.27 1.27)
				)
				(hide yes)
			)
		)
		(property "Author" "Antmicro"
			(at 246.38 100.33 0)
			(effects
				(font
					(size 1.27 1.27)
					(thickness 0.15)
				)
				(justify left bottom)
				(hide yes)
			)
		)
		(property "License" "Apache-2.0"
			(at 246.38 102.87 0)
			(effects
				(font
					(size 1.27 1.27)
					(thickness 0.15)
				)
				(justify left bottom)
				(hide yes)
			)
		)
		(pin "1"
		)
		(instances
			(project "com-express-7-baseboard"
				(path ""
					(reference "#PWR0160")
					(unit 1)
				)
			)
		)
	)
	(symbol
		(lib_id "antmicropower:+3V3")
		(at 184.15 80.01 0)
		(unit 1)
		(exclude_from_sim no)
		(in_bom yes)
		(on_board yes)
		(dnp no)
		(fields_autoplaced yes)
		(property "Reference" "#PWR0156"
			(at 184.15 83.82 0)
			(effects
				(font
					(size 1.27 1.27)
				)
				(justify left bottom)
				(hide yes)
			)
		)
		(property "Value" "+3V3"
			(at 184.15 76.454 0)
			(effects
				(font
					(size 1.27 1.27)
				)
				(justify left bottom)
			)
		)
		(property "Footprint" ""
			(at 184.15 80.01 0)
			(effects
				(font
					(size 1.27 1.27)
				)
				(justify left bottom)
				(hide yes)
			)
		)
		(property "Datasheet" ""
			(at 184.15 80.01 0)
			(effects
				(font
					(size 1.27 1.27)
				)
				(justify left bottom)
				(hide yes)
			)
		)
		(property "Description" ""
			(at 184.15 80.01 0)
			(effects
				(font
					(size 1.27 1.27)
				)
				(hide yes)
			)
		)
		(property "Author" "Antmicro"
			(at 199.39 82.55 0)
			(effects
				(font
					(size 1.27 1.27)
					(thickness 0.15)
				)
				(justify left bottom)
				(hide yes)
			)
		)
		(property "License" "Apache-2.0"
			(at 199.39 85.09 0)
			(effects
				(font
					(size 1.27 1.27)
					(thickness 0.15)
				)
				(justify left bottom)
				(hide yes)
			)
		)
		(pin "1"
		)
		(instances
			(project "com-express-7-baseboard"
				(path ""
					(reference "#PWR0156")
					(unit 1)
				)
			)
		)
	)
	(symbol
		(lib_id "antmicroLEDIndicationDiscrete:LED_G_0603_LTST-C190GKT")
		(at 232.41 142.24 90)
		(unit 1)
		(exclude_from_sim no)
		(in_bom yes)
		(on_board yes)
		(dnp no)
		(property "Reference" "D13"
			(at 233.68 138.43 90)
			(effects
				(font
					(size 1.27 1.27)
				)
				(justify right)
			)
		)
		(property "Value" "LED_G_0603_LTST-C190GKT"
			(at 228.6 139.7 0)
			(effects
				(font
					(size 1.27 1.27)
					(thickness 0.15)
				)
				(justify left bottom)
				(hide yes)
			)
		)
		(property "Footprint" "antmicro-footprints:LED_0603_1608Metric_G"
			(at 242.57 119.38 0)
			(effects
				(font
					(size 1.27 1.27)
					(thickness 0.15)
				)
				(justify left bottom)
				(hide yes)
			)
		)
		(property "Datasheet" "https://media.digikey.com/pdf/Data%20Sheets/Lite-On%20PDFs/LTST-C190GKT.pdf"
			(at 245.11 119.38 0)
			(effects
				(font
					(size 1.27 1.27)
					(thickness 0.15)
				)
				(justify left bottom)
				(hide yes)
			)
		)
		(property "Description" ""
			(at 232.41 142.24 0)
			(effects
				(font
					(size 1.27 1.27)
				)
				(hide yes)
			)
		)
		(property "MPN" "LTST-C190GKT"
			(at 229.235 136.525 90)
			(effects
				(font
					(size 1.27 1.27)
					(thickness 0.15)
				)
				(justify left bottom)
				(hide yes)
			)
		)
		(property "Manufacturer" "Lite-On"
			(at 250.19 119.38 0)
			(effects
				(font
					(size 1.27 1.27)
					(thickness 0.15)
				)
				(justify left bottom)
				(hide yes)
			)
		)
		(property "Author" "Antmicro"
			(at 252.73 119.38 0)
			(effects
				(font
					(size 1.27 1.27)
					(thickness 0.15)
				)
				(justify left bottom)
				(hide yes)
			)
		)
		(property "License" "Apache-2.0"
			(at 255.27 119.38 0)
			(effects
				(font
					(size 1.27 1.27)
					(thickness 0.15)
				)
				(justify left bottom)
				(hide yes)
			)
		)
		(property "Public" "False"
			(at 250.19 121.92 0)
			(effects
				(font
					(size 1.27 1.27)
				)
				(justify left bottom)
				(hide yes)
			)
		)
		(property "Color" "Green"
			(at 233.68 140.97 90)
			(effects
				(font
					(size 1.27 1.27)
				)
				(justify right)
			)
		)
		(pin "1"
		)
		(pin "2"
		)
		(instances
			(project "com-express-7-baseboard"
				(path ""
					(reference "D13")
					(unit 1)
				)
			)
		)
	)
	(symbol
		(lib_id "antmicroCapacitors0603:C_22u_16V_0603")
		(at 247.65 91.44 90)
		(unit 1)
		(exclude_from_sim no)
		(in_bom yes)
		(on_board yes)
		(dnp no)
		(fields_autoplaced yes)
		(property "Reference" "C72"
			(at 250.19 87.6235 90)
			(effects
				(font
					(size 1.27 1.27)
					(thickness 0.15)
				)
				(justify right)
			)
		)
		(property "Value" "C_22u_16V_0603"
			(at 257.81 71.12 0)
			(effects
				(font
					(size 1.27 1.27)
					(thickness 0.15)
				)
				(justify left bottom)
				(hide yes)
			)
		)
		(property "Footprint" "antmicro-footprints:C_0603_1608Metric"
			(at 260.35 71.12 0)
			(effects
				(font
					(size 1.27 1.27)
					(thickness 0.15)
				)
				(justify left bottom)
				(hide yes)
			)
		)
		(property "Datasheet" "https://product.samsungsem.com/mlcc/CL10A226MO7JZN.do"
			(at 262.89 71.12 0)
			(effects
				(font
					(size 1.27 1.27)
					(thickness 0.15)
				)
				(justify left bottom)
				(hide yes)
			)
		)
		(property "Description" ""
			(at 247.65 91.44 0)
			(effects
				(font
					(size 1.27 1.27)
				)
				(hide yes)
			)
		)
		(property "MPN" "CL10A226MO7JZNC"
			(at 265.43 71.12 0)
			(effects
				(font
					(size 1.27 1.27)
					(thickness 0.15)
				)
				(justify left bottom)
				(hide yes)
			)
		)
		(property "Manufacturer" "Samsung Electro-Mechanics"
			(at 267.97 71.12 0)
			(effects
				(font
					(size 1.27 1.27)
					(thickness 0.15)
				)
				(justify left bottom)
				(hide yes)
			)
		)
		(property "License" "Apache-2.0"
			(at 270.51 71.12 0)
			(effects
				(font
					(size 1.27 1.27)
					(thickness 0.15)
				)
				(justify left bottom)
				(hide yes)
			)
		)
		(property "Author" "Antmicro"
			(at 273.05 71.12 0)
			(effects
				(font
					(size 1.27 1.27)
					(thickness 0.15)
				)
				(justify left bottom)
				(hide yes)
			)
		)
		(property "Val" "22u"
			(at 250.19 90.1635 90)
			(effects
				(font
					(size 1.27 1.27)
					(thickness 0.15)
				)
				(justify right)
			)
		)
		(property "Voltage" "16V"
			(at 275.59 71.12 0)
			(effects
				(font
					(size 1.27 1.27)
				)
				(justify left bottom)
				(hide yes)
			)
		)
		(property "Dielectric" ""
			(at 278.13 71.12 0)
			(effects
				(font
					(size 1.27 1.27)
				)
				(justify left bottom)
				(hide yes)
			)
		)
		(property "Public" "False"
			(at 280.67 71.12 0)
			(effects
				(font
					(size 1.27 1.27)
				)
				(justify left bottom)
				(hide yes)
			)
		)
		(pin "2"
		)
		(pin "1"
		)
		(instances
			(project "com-express-7-baseboard"
				(path ""
					(reference "C72")
					(unit 1)
				)
			)
		)
	)
	(symbol
		(lib_id "antmicroPciConnectors:Bus_M.2_MDT180M03001")
		(at 200.66 88.9 0)
		(unit 1)
		(exclude_from_sim no)
		(in_bom yes)
		(on_board yes)
		(dnp no)
		(fields_autoplaced yes)
		(property "Reference" "J5"
			(at 215.9 81.28 0)
			(effects
				(font
					(size 1.27 1.27)
					(thickness 0.15)
				)
			)
		)
		(property "Value" "Bus_M.2_MDT180M03001"
			(at 246.38 96.52 0)
			(effects
				(font
					(size 1.27 1.27)
					(thickness 0.15)
				)
				(justify left bottom)
				(hide yes)
			)
		)
		(property "Footprint" "antmicro-footprints:Bus_M.2_Socket_Key_M_Amphenol_MDT180M03001"
			(at 246.38 99.06 0)
			(effects
				(font
					(size 1.27 1.27)
					(thickness 0.15)
				)
				(justify left bottom)
				(hide yes)
			)
		)
		(property "Datasheet" "https://cdn.amphenol-cs.com/media/wysiwyg/files/drawing/mdt180xxx001.pdf"
			(at 246.38 101.6 0)
			(effects
				(font
					(size 1.27 1.27)
					(thickness 0.15)
				)
				(justify left bottom)
				(hide yes)
			)
		)
		(property "Description" ""
			(at 200.66 88.9 0)
			(effects
				(font
					(size 1.27 1.27)
				)
				(hide yes)
			)
		)
		(property "Manufacturer" "Amphenol"
			(at 246.38 104.14 0)
			(effects
				(font
					(size 1.27 1.27)
					(thickness 0.15)
				)
				(justify left bottom)
				(hide yes)
			)
		)
		(property "MPN" "MDT180M03001"
			(at 215.9 83.82 0)
			(effects
				(font
					(size 1.27 1.27)
					(thickness 0.15)
				)
			)
		)
		(property "Author" "Antmicro"
			(at 246.38 106.68 0)
			(effects
				(font
					(size 1.27 1.27)
					(thickness 0.15)
				)
				(justify left bottom)
				(hide yes)
			)
		)
		(property "License" "Apache-2.0"
			(at 246.38 109.22 0)
			(effects
				(font
					(size 1.27 1.27)
					(thickness 0.15)
				)
				(justify left bottom)
				(hide yes)
			)
		)
		(pin "44"
		)
		(pin "34"
		)
		(pin "50"
		)
		(pin "29"
		)
		(pin "31"
		)
		(pin "49"
		)
		(pin "30"
		)
		(pin "56"
		)
		(pin "55"
		)
		(pin "67"
		)
		(pin "6"
		)
		(pin "54"
		)
		(pin "7"
		)
		(pin "58"
		)
		(pin "68"
		)
		(pin "69"
		)
		(pin "51"
		)
		(pin "5"
		)
		(pin "12"
		)
		(pin "45"
		)
		(pin "46"
		)
		(pin "25"
		)
		(pin "15"
		)
		(pin "28"
		)
		(pin "48"
		)
		(pin "26"
		)
		(pin "3"
		)
		(pin "13"
		)
		(pin "37"
		)
		(pin "33"
		)
		(pin "20"
		)
		(pin "27"
		)
		(pin "11"
		)
		(pin "32"
		)
		(pin "24"
		)
		(pin "47"
		)
		(pin "14"
		)
		(pin "10"
		)
		(pin "43"
		)
		(pin "9"
		)
		(pin "74"
		)
		(pin "39"
		)
		(pin "38"
		)
		(pin "8"
		)
		(pin "53"
		)
		(pin "72"
		)
		(pin "SH"
		)
		(pin "40"
		)
		(pin "42"
		)
		(pin "41"
		)
		(pin "1"
		)
		(pin "23"
		)
		(pin "35"
		)
		(pin "22"
		)
		(pin "75"
		)
		(pin "17"
		)
		(pin "71"
		)
		(pin "52"
		)
		(pin "4"
		)
		(pin "73"
		)
		(pin "57"
		)
		(pin "19"
		)
		(pin "18"
		)
		(pin "16"
		)
		(pin "2"
		)
		(pin "70"
		)
		(pin "21"
		)
		(pin "36"
		)
		(instances
			(project "com-express-7-baseboard"
				(path ""
					(reference "J5")
					(unit 1)
				)
			)
		)
	)
	(symbol
		(lib_id "antmicroCapacitors0603:C_22u_16V_0603")
		(at 237.49 91.44 90)
		(unit 1)
		(exclude_from_sim no)
		(in_bom yes)
		(on_board yes)
		(dnp no)
		(fields_autoplaced yes)
		(property "Reference" "C71"
			(at 240.03 87.6235 90)
			(effects
				(font
					(size 1.27 1.27)
					(thickness 0.15)
				)
				(justify right)
			)
		)
		(property "Value" "C_22u_16V_0603"
			(at 247.65 71.12 0)
			(effects
				(font
					(size 1.27 1.27)
					(thickness 0.15)
				)
				(justify left bottom)
				(hide yes)
			)
		)
		(property "Footprint" "antmicro-footprints:C_0603_1608Metric"
			(at 250.19 71.12 0)
			(effects
				(font
					(size 1.27 1.27)
					(thickness 0.15)
				)
				(justify left bottom)
				(hide yes)
			)
		)
		(property "Datasheet" "https://product.samsungsem.com/mlcc/CL10A226MO7JZN.do"
			(at 252.73 71.12 0)
			(effects
				(font
					(size 1.27 1.27)
					(thickness 0.15)
				)
				(justify left bottom)
				(hide yes)
			)
		)
		(property "Description" ""
			(at 237.49 91.44 0)
			(effects
				(font
					(size 1.27 1.27)
				)
				(hide yes)
			)
		)
		(property "MPN" "CL10A226MO7JZNC"
			(at 255.27 71.12 0)
			(effects
				(font
					(size 1.27 1.27)
					(thickness 0.15)
				)
				(justify left bottom)
				(hide yes)
			)
		)
		(property "Manufacturer" "Samsung Electro-Mechanics"
			(at 257.81 71.12 0)
			(effects
				(font
					(size 1.27 1.27)
					(thickness 0.15)
				)
				(justify left bottom)
				(hide yes)
			)
		)
		(property "License" "Apache-2.0"
			(at 260.35 71.12 0)
			(effects
				(font
					(size 1.27 1.27)
					(thickness 0.15)
				)
				(justify left bottom)
				(hide yes)
			)
		)
		(property "Author" "Antmicro"
			(at 262.89 71.12 0)
			(effects
				(font
					(size 1.27 1.27)
					(thickness 0.15)
				)
				(justify left bottom)
				(hide yes)
			)
		)
		(property "Val" "22u"
			(at 240.03 90.1635 90)
			(effects
				(font
					(size 1.27 1.27)
					(thickness 0.15)
				)
				(justify right)
			)
		)
		(property "Voltage" "16V"
			(at 265.43 71.12 0)
			(effects
				(font
					(size 1.27 1.27)
				)
				(justify left bottom)
				(hide yes)
			)
		)
		(property "Dielectric" ""
			(at 267.97 71.12 0)
			(effects
				(font
					(size 1.27 1.27)
				)
				(justify left bottom)
				(hide yes)
			)
		)
		(property "Public" "False"
			(at 270.51 71.12 0)
			(effects
				(font
					(size 1.27 1.27)
				)
				(justify left bottom)
				(hide yes)
			)
		)
		(pin "2"
		)
		(pin "1"
		)
		(instances
			(project "com-express-7-baseboard"
				(path ""
					(reference "C71")
					(unit 1)
				)
			)
		)
	)
	(symbol
		(lib_id "antmicropower:GND")
		(at 247.65 92.71 0)
		(unit 1)
		(exclude_from_sim no)
		(in_bom yes)
		(on_board yes)
		(dnp no)
		(property "Reference" "#PWR0161"
			(at 247.65 99.06 0)
			(effects
				(font
					(size 1.27 1.27)
				)
				(justify left bottom)
				(hide yes)
			)
		)
		(property "Value" "GND"
			(at 245.745 97.79 0)
			(effects
				(font
					(size 1.27 1.27)
				)
				(justify left bottom)
			)
		)
		(property "Footprint" ""
			(at 247.65 92.71 0)
			(effects
				(font
					(size 1.27 1.27)
				)
				(justify left bottom)
				(hide yes)
			)
		)
		(property "Datasheet" ""
			(at 247.65 92.71 0)
			(effects
				(font
					(size 1.27 1.27)
				)
				(justify left bottom)
				(hide yes)
			)
		)
		(property "Description" ""
			(at 247.65 92.71 0)
			(effects
				(font
					(size 1.27 1.27)
				)
				(hide yes)
			)
		)
		(property "Author" "Antmicro"
			(at 256.54 100.33 0)
			(effects
				(font
					(size 1.27 1.27)
					(thickness 0.15)
				)
				(justify left bottom)
				(hide yes)
			)
		)
		(property "License" "Apache-2.0"
			(at 256.54 102.87 0)
			(effects
				(font
					(size 1.27 1.27)
					(thickness 0.15)
				)
				(justify left bottom)
				(hide yes)
			)
		)
		(pin "1"
		)
		(instances
			(project "com-express-7-baseboard"
				(path ""
					(reference "#PWR0161")
					(unit 1)
				)
			)
		)
	)
	(symbol
		(lib_id "antmicropower:GND")
		(at 257.81 92.71 0)
		(unit 1)
		(exclude_from_sim no)
		(in_bom yes)
		(on_board yes)
		(dnp no)
		(property "Reference" "#PWR0162"
			(at 257.81 99.06 0)
			(effects
				(font
					(size 1.27 1.27)
				)
				(justify left bottom)
				(hide yes)
			)
		)
		(property "Value" "GND"
			(at 255.905 97.79 0)
			(effects
				(font
					(size 1.27 1.27)
				)
				(justify left bottom)
			)
		)
		(property "Footprint" ""
			(at 257.81 92.71 0)
			(effects
				(font
					(size 1.27 1.27)
				)
				(justify left bottom)
				(hide yes)
			)
		)
		(property "Datasheet" ""
			(at 257.81 92.71 0)
			(effects
				(font
					(size 1.27 1.27)
				)
				(justify left bottom)
				(hide yes)
			)
		)
		(property "Description" ""
			(at 257.81 92.71 0)
			(effects
				(font
					(size 1.27 1.27)
				)
				(hide yes)
			)
		)
		(property "Author" "Antmicro"
			(at 266.7 100.33 0)
			(effects
				(font
					(size 1.27 1.27)
					(thickness 0.15)
				)
				(justify left bottom)
				(hide yes)
			)
		)
		(property "License" "Apache-2.0"
			(at 266.7 102.87 0)
			(effects
				(font
					(size 1.27 1.27)
					(thickness 0.15)
				)
				(justify left bottom)
				(hide yes)
			)
		)
		(pin "1"
		)
		(instances
			(project "com-express-7-baseboard"
				(path ""
					(reference "#PWR0162")
					(unit 1)
				)
			)
		)
	)
	(symbol
		(lib_id "antmicroResistors0603:R_0R_22.4A_0603")
		(at 267.97 81.28 90)
		(unit 1)
		(exclude_from_sim no)
		(in_bom yes)
		(on_board yes)
		(dnp no)
		(fields_autoplaced yes)
		(property "Reference" "R125"
			(at 270.51 76.2 90)
			(effects
				(font
					(size 1.27 1.27)
				)
				(justify right)
			)
		)
		(property "Value" "R_0R_22.4A_0603"
			(at 270.51 77.47 90)
			(effects
				(font
					(size 1.27 1.27)
					(thickness 0.15)
				)
				(justify right)
				(hide yes)
			)
		)
		(property "Footprint" "antmicro-footprints:R_0603_1608Metric"
			(at 280.67 58.42 0)
			(effects
				(font
					(size 1.27 1.27)
					(thickness 0.15)
				)
				(justify left bottom)
				(hide yes)
			)
		)
		(property "Datasheet" "https://fscdn.rohm.com/en/products/databook/datasheet/passive/resistor/chip_resistor/pmr-jpw-e.pdf"
			(at 283.21 58.42 0)
			(effects
				(font
					(size 1.27 1.27)
					(thickness 0.15)
				)
				(justify left bottom)
				(hide yes)
			)
		)
		(property "Description" ""
			(at 267.97 81.28 0)
			(effects
				(font
					(size 1.27 1.27)
				)
				(hide yes)
			)
		)
		(property "Manufacturer" "ROHM Semiconductor"
			(at 285.75 58.42 0)
			(effects
				(font
					(size 1.27 1.27)
					(thickness 0.15)
				)
				(justify left bottom)
				(hide yes)
			)
		)
		(property "MPN" "PMR03EZPJ000"
			(at 288.29 58.42 0)
			(effects
				(font
					(size 1.27 1.27)
					(thickness 0.15)
				)
				(justify left bottom)
				(hide yes)
			)
		)
		(property "Val" "0R"
			(at 270.51 78.74 90)
			(effects
				(font
					(size 1.27 1.27)
					(thickness 0.15)
				)
				(justify right)
			)
		)
		(property "Author" "Antmicro"
			(at 290.83 58.42 0)
			(effects
				(font
					(size 1.27 1.27)
					(thickness 0.15)
				)
				(justify left bottom)
				(hide yes)
			)
		)
		(property "License" "Apache-2.0"
			(at 293.37 58.42 0)
			(effects
				(font
					(size 1.27 1.27)
					(thickness 0.15)
				)
				(justify left bottom)
				(hide yes)
			)
		)
		(property "Max. Curr." "22.4A"
			(at 270.51 81.28 90)
			(effects
				(font
					(size 1.27 1.27)
					(thickness 0.15)
				)
				(justify right)
			)
		)
		(property "Tolerance" "template_tolerance"
			(at 278.13 60.96 0)
			(effects
				(font
					(size 1.27 1.27)
				)
				(justify left bottom)
				(hide yes)
			)
		)
		(property "Public" "False"
			(at 298.45 60.96 0)
			(effects
				(font
					(size 1.27 1.27)
				)
				(justify left bottom)
				(hide yes)
			)
		)
		(pin "1"
		)
		(pin "2"
		)
		(instances
			(project "com-express-7-baseboard"
				(path ""
					(reference "R125")
					(unit 1)
				)
			)
		)
	)
	(symbol
		(lib_id "antmicroModules:Mech_M2_2280_H2.5mm")
		(at 210.82 182.88 0)
		(unit 1)
		(exclude_from_sim no)
		(in_bom no)
		(on_board yes)
		(dnp no)
		(fields_autoplaced yes)
		(property "Reference" "A2"
			(at 222.25 184.7849 0)
			(effects
				(font
					(size 1.27 1.27)
					(thickness 0.15)
				)
				(justify left)
			)
		)
		(property "Value" "Mech_M2_2280_H2.5mm"
			(at 222.25 187.3249 0)
			(effects
				(font
					(size 1.27 1.27)
					(thickness 0.15)
				)
				(justify left)
			)
		)
		(property "Footprint" "antmicro-footprints:Mech_M2_2280_H2.5mm"
			(at 236.22 187.96 0)
			(effects
				(font
					(size 1.27 1.27)
					(thickness 0.15)
				)
				(justify left bottom)
				(hide yes)
			)
		)
		(property "Datasheet" ""
			(at 236.22 190.5 0)
			(effects
				(font
					(size 1.27 1.27)
					(thickness 0.15)
				)
				(justify left bottom)
				(hide yes)
			)
		)
		(property "Description" ""
			(at 210.82 182.88 0)
			(effects
				(font
					(size 1.27 1.27)
				)
				(hide yes)
			)
		)
		(property "Manufacturer" ""
			(at 210.82 182.88 0)
			(effects
				(font
					(size 1.27 1.27)
				)
				(hide yes)
			)
		)
		(property "MPN" ""
			(at 210.82 182.88 0)
			(effects
				(font
					(size 1.27 1.27)
				)
			)
		)
		(property "Author" "Antmicro"
			(at 236.22 193.04 0)
			(effects
				(font
					(size 1.27 1.27)
					(thickness 0.15)
				)
				(justify left bottom)
				(hide yes)
			)
		)
		(property "License" "Apache-2.0"
			(at 236.22 195.58 0)
			(effects
				(font
					(size 1.27 1.27)
					(thickness 0.15)
				)
				(justify left bottom)
				(hide yes)
			)
		)
		(property "Public" "False"
			(at 236.22 198.12 0)
			(effects
				(font
					(size 1.27 1.27)
				)
				(justify left bottom)
				(hide yes)
			)
		)
		(instances
			(project "com-express-7-baseboard"
				(path ""
					(reference "A2")
					(unit 1)
				)
			)
		)
	)
	(symbol
		(lib_id "antmicropower:GND")
		(at 232.41 167.64 0)
		(unit 1)
		(exclude_from_sim no)
		(in_bom yes)
		(on_board yes)
		(dnp no)
		(property "Reference" "#PWR0159"
			(at 232.41 173.99 0)
			(effects
				(font
					(size 1.27 1.27)
				)
				(justify left bottom)
				(hide yes)
			)
		)
		(property "Value" "GND"
			(at 230.505 172.72 0)
			(effects
				(font
					(size 1.27 1.27)
				)
				(justify left bottom)
			)
		)
		(property "Footprint" ""
			(at 232.41 167.64 0)
			(effects
				(font
					(size 1.27 1.27)
				)
				(justify left bottom)
				(hide yes)
			)
		)
		(property "Datasheet" ""
			(at 232.41 167.64 0)
			(effects
				(font
					(size 1.27 1.27)
				)
				(justify left bottom)
				(hide yes)
			)
		)
		(property "Description" ""
			(at 232.41 167.64 0)
			(effects
				(font
					(size 1.27 1.27)
				)
				(hide yes)
			)
		)
		(property "Author" "Antmicro"
			(at 241.3 175.26 0)
			(effects
				(font
					(size 1.27 1.27)
					(thickness 0.15)
				)
				(justify left bottom)
				(hide yes)
			)
		)
		(property "License" "Apache-2.0"
			(at 241.3 177.8 0)
			(effects
				(font
					(size 1.27 1.27)
					(thickness 0.15)
				)
				(justify left bottom)
				(hide yes)
			)
		)
		(pin "1"
		)
		(instances
			(project "com-express-7-baseboard"
				(path ""
					(reference "#PWR0159")
					(unit 1)
				)
			)
		)
	)
)
